# S9S_MB_2U (Grand Teton) — schematic netlist excerpt (pin names and nets, part order shuffled) for the footprints in the layout excerpt that follows; sources: Cadence DE-HDL packaged netlist, KiCad conversion of 03242023_DA0F0TMBIJ0_F0T_Motherboard_J_brd_V01_OCP.brd

C400  Q_CAP  22UF 4V 20% X6S  pkg C0402  page 74 : A = PVCCFA_EHV_FIVRA_CPU0 ; B = GND
C305  Q_CAP  22UF 4V 20% X6S  pkg C0402  page 77 : A = PVCCIN_CPU1 ; B = GND

(kicad_pcb
	(version 20260206)
	(generator "pcbnew")
	(generator_version "10.0")
	(general
		(thickness 1.6)
		(legacy_teardrops no)
	)
	(paper "A4")
	(title_block
		(title "03242023_DA0F0TMBIJ0_F0T_Motherboard_J_brd_V01_OCP.brd")
		(comment 1 "Grand Teton / footprints 3242-3243 of 6105")
	)
	(layers
		(0 "F.Cu" signal "TOP")
		(4 "In1.Cu" signal "GND")
		(6 "In2.Cu" signal "IN1")
		(8 "In3.Cu" signal "GND1")
		(10 "In4.Cu" signal "IN2")
		(12 "In5.Cu" signal "GND2")
		(14 "In6.Cu" signal "IN3")
		(16 "In7.Cu" signal "GND3")
		(18 "In8.Cu" signal "VCC")
		(20 "In9.Cu" signal "VCC1")
		(22 "In10.Cu" signal "GND4")
		(24 "In11.Cu" signal "IN4")
		(26 "In12.Cu" signal "GND5")
		(28 "In13.Cu" signal "IN5")
		(30 "In14.Cu" signal "GND6")
		(32 "In15.Cu" signal "IN6")
		(34 "In16.Cu" signal "GND7")
		(2 "B.Cu" signal "BOTTOM")
		(9 "F.Adhes" user "F.Adhesive")
		(11 "B.Adhes" user "B.Adhesive")
		(13 "F.Paste" user "Package Geometry/Pastemask Top")
		(15 "B.Paste" user "Package Geometry/Pastemask Bottom")
		(5 "F.SilkS" user "Ref Des/Silkscreen Top")
		(7 "B.SilkS" user "Ref Des/Silkscreen Bottom")
		(1 "F.Mask" user "Board Geometry/Soldermask Top")
		(3 "B.Mask" user "Board Geometry/Soldermask Bottom")
		(17 "Dwgs.User" user "User.Drawings")
		(19 "Cmts.User" user "User.Comments")
		(21 "Eco1.User" user "User.Eco1")
		(23 "Eco2.User" user "User.Eco2")
		(25 "Edge.Cuts" user "Board Geometry/Outline")
		(27 "Margin" user)
		(31 "F.CrtYd" user "Package Geometry/Place Bound Top")
		(29 "B.CrtYd" user "Package Geometry/Place Bound Bottom")
		(35 "F.Fab" user "Ref Des/Assembly Top")
		(33 "B.Fab" user "Ref Des/Assembly Bottom")
	)
	(footprint ""
		(layer "F.Cu")
		(at 116.561616 -255.0541 90)
		(property "Reference" "C305"
			(at 0 0 90)
			(layer "F.SilkS")
			(hide yes)
			(effects
				(font
					(size 1.27 1.27)
				)
			)
		)
		(property "Value" ""
			(at 0 0 90)
			(layer "F.Fab")
			(effects
				(font
					(size 1.27 1.27)
				)
			)
		)
		(duplicate_pad_numbers_are_jumpers no)
		(fp_line
			(start 0.7874 -0.4064)
			(end 0.7874 0.4064)
			(stroke
				(width 0.1524)
				(type default)
			)
			(layer "F.SilkS")
		)
		(fp_line
			(start -0.7874 -0.4064)
			(end 0.7874 -0.4064)
			(stroke
				(width 0.1524)
				(type default)
			)
			(layer "F.SilkS")
		)
		(fp_line
			(start 0.7874 0.4064)
			(end -0.7874 0.4064)
			(stroke
				(width 0.1524)
				(type default)
			)
			(layer "F.SilkS")
		)
		(fp_line
			(start -0.7874 0.4064)
			(end -0.7874 -0.4064)
			(stroke
				(width 0.1524)
				(type default)
			)
			(layer "F.SilkS")
		)
		(fp_line
			(start -0.12065 -0.305054)
			(end -0.12065 -0.2794)
			(stroke
				(width 0.1)
				(type default)
			)
			(layer "F.Fab")
		)
		(fp_line
			(start -0.67945 -0.305054)
			(end -0.12065 -0.305054)
			(stroke
				(width 0.1)
				(type default)
			)
			(layer "F.Fab")
		)
		(fp_line
			(start 0.67945 -0.3048)
			(end 0.67945 0.3048)
			(stroke
				(width 0.1)
				(type default)
			)
			(layer "F.Fab")
		)
		(fp_line
			(start 0.12065 -0.3048)
			(end 0.67945 -0.3048)
			(stroke
				(width 0.1)
				(type default)
			)
			(layer "F.Fab")
		)
		(fp_line
			(start 0.12065 -0.2794)
			(end 0.12065 -0.3048)
			(stroke
				(width 0.1)
				(type default)
			)
			(layer "F.Fab")
		)
		(fp_line
			(start -0.12065 -0.2794)
			(end 0.12065 -0.2794)
			(stroke
				(width 0.1)
				(type default)
			)
			(layer "F.Fab")
		)
		(fp_line
			(start 0.120396 0.2794)
			(end -0.12065 0.2794)
			(stroke
				(width 0.1)
				(type default)
			)
			(layer "F.Fab")
		)
		(fp_line
			(start -0.12065 0.2794)
			(end -0.12065 0.3048)
			(stroke
				(width 0.1)
				(type default)
			)
			(layer "F.Fab")
		)
		(fp_line
			(start 0.67945 0.3048)
			(end 0.120396 0.3048)
			(stroke
				(width 0.1)
				(type default)
			)
			(layer "F.Fab")
		)
		(fp_line
			(start 0.120396 0.3048)
			(end 0.120396 0.2794)
			(stroke
				(width 0.1)
				(type default)
			)
			(layer "F.Fab")
		)
		(fp_line
			(start -0.12065 0.3048)
			(end -0.67945 0.3048)
			(stroke
				(width 0.1)
				(type default)
			)
			(layer "F.Fab")
		)
		(fp_line
			(start -0.67945 0.3048)
			(end -0.67945 -0.305054)
			(stroke
				(width 0.1)
				(type default)
			)
			(layer "F.Fab")
		)
		(pad "1" smd circle
			(at -0.40005 0 90)
			(size 0 0)
			(layers "F.Cu" "F.Mask" "F.Paste")
			(net "PVCCIN_CPU1")
		)
		(pad "2" smd circle
			(at 0.40005 0 90)
			(size 0 0)
			(layers "F.Cu" "F.Mask" "F.Paste")
			(net "GND")
		)
	)
	(footprint ""
		(layer "F.Cu")
		(at 354.261928 -260.364986 -90)
		(property "Reference" "C400"
			(at 0 0 270)
			(layer "F.SilkS")
			(hide yes)
			(effects
				(font
					(size 1.27 1.27)
				)
			)
		)
		(property "Value" ""
			(at 0 0 270)
			(layer "F.Fab")
			(effects
				(font
					(size 1.27 1.27)
				)
			)
		)
		(duplicate_pad_numbers_are_jumpers no)
		(fp_line
			(start -0.7874 0.4064)
			(end -0.7874 -0.4064)
			(stroke
				(width 0.1524)
				(type default)
			)
			(layer "F.SilkS")
		)
		(fp_line
			(start 0.7874 0.4064)
			(end -0.7874 0.4064)
			(stroke
				(width 0.1524)
				(type default)
			)
			(layer "F.SilkS")
		)
		(fp_line
			(start -0.7874 -0.4064)
			(end 0.7874 -0.4064)
			(stroke
				(width 0.1524)
				(type default)
			)
			(layer "F.SilkS")
		)
		(fp_line
			(start 0.7874 -0.4064)
			(end 0.7874 0.4064)
			(stroke
				(width 0.1524)
				(type default)
			)
			(layer "F.SilkS")
		)
		(fp_line
			(start -0.67945 0.3048)
			(end -0.67945 -0.305054)
			(stroke
				(width 0.1)
				(type default)
			)
			(layer "F.Fab")
		)
		(fp_line
			(start -0.12065 0.3048)
			(end -0.67945 0.3048)
			(stroke
				(width 0.1)
				(type default)
			)
			(layer "F.Fab")
		)
		(fp_line
			(start 0.120396 0.3048)
			(end 0.120396 0.2794)
			(stroke
				(width 0.1)
				(type default)
			)
			(layer "F.Fab")
		)
		(fp_line
			(start 0.67945 0.3048)
			(end 0.120396 0.3048)
			(stroke
				(width 0.1)
				(type default)
			)
			(layer "F.Fab")
		)
		(fp_line
			(start -0.12065 0.2794)
			(end -0.12065 0.3048)
			(stroke
				(width 0.1)
				(type default)
			)
			(layer "F.Fab")
		)
		(fp_line
			(start 0.120396 0.2794)
			(end -0.12065 0.2794)
			(stroke
				(width 0.1)
				(type default)
			)
			(layer "F.Fab")
		)
		(fp_line
			(start -0.12065 -0.2794)
			(end 0.12065 -0.2794)
			(stroke
				(width 0.1)
				(type default)
			)
			(layer "F.Fab")
		)
		(fp_line
			(start 0.12065 -0.2794)
			(end 0.12065 -0.3048)
			(stroke
				(width 0.1)
				(type default)
			)
			(layer "F.Fab")
		)
		(fp_line
			(start 0.12065 -0.3048)
			(end 0.67945 -0.3048)
			(stroke
				(width 0.1)
				(type default)
			)
			(layer "F.Fab")
		)
		(fp_line
			(start 0.67945 -0.3048)
			(end 0.67945 0.3048)
			(stroke
				(width 0.1)
				(type default)
			)
			(layer "F.Fab")
		)
		(fp_line
			(start -0.67945 -0.305054)
			(end -0.12065 -0.305054)
			(stroke
				(width 0.1)
				(type default)
			)
			(layer "F.Fab")
		)
		(fp_line
			(start -0.12065 -0.305054)
			(end -0.12065 -0.2794)
			(stroke
				(width 0.1)
				(type default)
			)
			(layer "F.Fab")
		)
		(pad "1" smd circle
			(at -0.40005 0 270)
			(size 0 0)
			(layers "F.Cu" "F.Mask" "F.Paste")
			(net "PVCCFA_EHV_FIVRA_CPU0")
		)
		(pad "2" smd circle
			(at 0.40005 0 270)
			(size 0 0)
			(layers "F.Cu" "F.Mask" "F.Paste")
			(net "GND")
		)
	)
)
